# T6G (Grand Teton) — schematic netlist excerpt (pin names and nets, part order shuffled) for the footprints in the layout excerpt that follows; sources: Cadence DE-HDL packaged netlist, KiCad conversion of 04192023_DAF0TMB3IC0_F0TG_MB_C_brd_V02_OCP.brd

C1536  Q_CAP_DIFFBUS  DIFF BUS_0.22UF 6.3V 20% X6S  pkg C0201  page 67 : \1\ = P5E_CPU1_P3_TX_C_DN<5> ; \2\ = P5E_CPU1_P3_TX_DN<5>
C926  Q_CAP_DIFFBUS  DIFF BUS_0.22UF 6.3V 20% X6S  pkg C0201  page 63 : \1\ = P5E_CPU0_P0_TX_C_DN<3> ; \2\ = P5E_CPU0_P0_TX_DN<3>
R1090  Q_RES  2.2K 5% CHIP  pkg 0402LF  page 250 : A = P3V3_AUX ; B = SMB_SENSOR_M2_P1_3V3AUX_SDA
R599  Q_RES  0 5% CHIP  pkg 0201LF  page 320 : A = CLK_100M_RETIMER_CPU1_P0_R_DP ; B = CLK_100M_RETIMER_CPU1_P0_DP

(kicad_pcb
	(version 20260206)
	(generator "pcbnew")
	(generator_version "10.0")
	(general
		(thickness 1.6)
		(legacy_teardrops no)
	)
	(paper "A4")
	(title_block
		(title "04192023_DAF0TMB3IC0_F0TG_MB_C_brd_V02_OCP.brd")
		(comment 1 "Grand Teton / footprints 4438-4441 of 8354")
	)
	(layers
		(0 "F.Cu" signal "TOP")
		(4 "In1.Cu" signal "GND")
		(6 "In2.Cu" signal "IN1")
		(8 "In3.Cu" signal "GND1")
		(10 "In4.Cu" signal "IN2")
		(12 "In5.Cu" signal "GND2")
		(14 "In6.Cu" signal "IN3")
		(16 "In7.Cu" signal "GND3")
		(18 "In8.Cu" signal "VCC")
		(20 "In9.Cu" signal "VCC1")
		(22 "In10.Cu" signal "GND4")
		(24 "In11.Cu" signal "IN4")
		(26 "In12.Cu" signal "GND5")
		(28 "In13.Cu" signal "IN5")
		(30 "In14.Cu" signal "GND6")
		(32 "In15.Cu" signal "IN6")
		(34 "In16.Cu" signal "GND7")
		(2 "B.Cu" signal "BOTTOM")
		(9 "F.Adhes" user "F.Adhesive")
		(11 "B.Adhes" user "B.Adhesive")
		(13 "F.Paste" user "Package Geometry/Pastemask Top")
		(15 "B.Paste" user "Package Geometry/Pastemask Bottom")
		(5 "F.SilkS" user "Ref Des/Silkscreen Top")
		(7 "B.SilkS" user "Ref Des/Silkscreen Bottom")
		(1 "F.Mask" user "Board Geometry/Soldermask Top")
		(3 "B.Mask" user "Board Geometry/Soldermask Bottom")
		(17 "Dwgs.User" user "User.Drawings")
		(19 "Cmts.User" user "User.Comments")
		(21 "Eco1.User" user "User.Eco1")
		(23 "Eco2.User" user "User.Eco2")
		(25 "Edge.Cuts" user "Board Geometry/Outline")
		(27 "Margin" user)
		(31 "F.CrtYd" user "Package Geometry/Place Bound Top")
		(29 "B.CrtYd" user "Package Geometry/Place Bound Bottom")
		(35 "F.Fab" user "Ref Des/Assembly Top")
		(33 "B.Fab" user "Ref Des/Assembly Bottom")
	)
	(footprint ""
		(layer "F.Cu")
		(at 277.352252 -116.10467)
		(property "Reference" "R1090"
			(at 0 0 0)
			(layer "F.SilkS")
			(hide yes)
			(effects
				(font
					(size 1.27 1.27)
				)
			)
		)
		(property "Value" ""
			(at 0 0 0)
			(layer "F.Fab")
			(effects
				(font
					(size 1.27 1.27)
				)
			)
		)
		(duplicate_pad_numbers_are_jumpers no)
		(fp_line
			(start -0.7874 -0.4064)
			(end 0.7874 -0.4064)
			(stroke
				(width 0.1524)
				(type default)
			)
			(layer "F.SilkS")
		)
		(fp_line
			(start -0.7874 0.4064)
			(end -0.7874 -0.4064)
			(stroke
				(width 0.1524)
				(type default)
			)
			(layer "F.SilkS")
		)
		(fp_line
			(start 0.7874 -0.4064)
			(end 0.7874 0.4064)
			(stroke
				(width 0.1524)
				(type default)
			)
			(layer "F.SilkS")
		)
		(fp_line
			(start 0.7874 0.4064)
			(end -0.7874 0.4064)
			(stroke
				(width 0.1524)
				(type default)
			)
			(layer "F.SilkS")
		)
		(fp_line
			(start -0.67945 -0.305054)
			(end -0.12065 -0.305054)
			(stroke
				(width 0.1)
				(type default)
			)
			(layer "F.Fab")
		)
		(fp_line
			(start -0.67945 0.3048)
			(end -0.67945 -0.305054)
			(stroke
				(width 0.1)
				(type default)
			)
			(layer "F.Fab")
		)
		(fp_line
			(start -0.12065 -0.305054)
			(end -0.12065 -0.2794)
			(stroke
				(width 0.1)
				(type default)
			)
			(layer "F.Fab")
		)
		(fp_line
			(start -0.12065 -0.2794)
			(end 0.12065 -0.2794)
			(stroke
				(width 0.1)
				(type default)
			)
			(layer "F.Fab")
		)
		(fp_line
			(start -0.12065 0.2794)
			(end -0.12065 0.3048)
			(stroke
				(width 0.1)
				(type default)
			)
			(layer "F.Fab")
		)
		(fp_line
			(start -0.12065 0.3048)
			(end -0.67945 0.3048)
			(stroke
				(width 0.1)
				(type default)
			)
			(layer "F.Fab")
		)
		(fp_line
			(start 0.120396 0.2794)
			(end -0.12065 0.2794)
			(stroke
				(width 0.1)
				(type default)
			)
			(layer "F.Fab")
		)
		(fp_line
			(start 0.120396 0.3048)
			(end 0.120396 0.2794)
			(stroke
				(width 0.1)
				(type default)
			)
			(layer "F.Fab")
		)
		(fp_line
			(start 0.12065 -0.3048)
			(end 0.67945 -0.3048)
			(stroke
				(width 0.1)
				(type default)
			)
			(layer "F.Fab")
		)
		(fp_line
			(start 0.12065 -0.2794)
			(end 0.12065 -0.3048)
			(stroke
				(width 0.1)
				(type default)
			)
			(layer "F.Fab")
		)
		(fp_line
			(start 0.67945 -0.3048)
			(end 0.67945 0.3048)
			(stroke
				(width 0.1)
				(type default)
			)
			(layer "F.Fab")
		)
		(fp_line
			(start 0.67945 0.3048)
			(end 0.120396 0.3048)
			(stroke
				(width 0.1)
				(type default)
			)
			(layer "F.Fab")
		)
		(pad "1" smd circle
			(at -0.40005 0)
			(size 0 0)
			(layers "F.Cu" "F.Mask" "F.Paste")
			(net "P3V3_AUX")
		)
		(pad "2" smd circle
			(at 0.40005 0)
			(size 0 0)
			(layers "F.Cu" "F.Mask" "F.Paste")
			(net "SMB_SENSOR_M2_P1_3V3AUX_SDA")
		)
	)
	(footprint ""
		(layer "F.Cu")
		(at 117.811296 -373.03583 -90)
		(property "Reference" "C1536"
			(at 0 0 270)
			(layer "F.SilkS")
			(hide yes)
			(effects
				(font
					(size 1.27 1.27)
				)
			)
		)
		(property "Value" ""
			(at 0 0 270)
			(layer "F.Fab")
			(effects
				(font
					(size 1.27 1.27)
				)
			)
		)
		(duplicate_pad_numbers_are_jumpers no)
		(fp_line
			(start -0.299974 0.150114)
			(end -0.299974 -0.150114)
			(stroke
				(width 0.1)
				(type default)
			)
			(layer "F.Fab")
		)
		(fp_line
			(start 0.299974 0.150114)
			(end -0.299974 0.150114)
			(stroke
				(width 0.1)
				(type default)
			)
			(layer "F.Fab")
		)
		(fp_line
			(start -0.299974 -0.150114)
			(end 0.299974 -0.150114)
			(stroke
				(width 0.1)
				(type default)
			)
			(layer "F.Fab")
		)
		(fp_line
			(start 0.299974 -0.150114)
			(end 0.299974 0.150114)
			(stroke
				(width 0.1)
				(type default)
			)
			(layer "F.Fab")
		)
		(pad "1" smd rect
			(at -0.2667 0 270)
			(size 0.3048 0.381)
			(layers "F.Cu" "F.Mask" "F.Paste")
			(net "P5E_CPU1_P3_TX_C_DN<5>")
		)
		(pad "2" smd rect
			(at 0.2667 0 270)
			(size 0.3048 0.381)
			(layers "F.Cu" "F.Mask" "F.Paste")
			(net "P5E_CPU1_P3_TX_DN<5>")
		)
	)
	(footprint ""
		(layer "F.Cu")
		(at 301.605696 -378.95403 -90)
		(property "Reference" "C926"
			(at 0 0 270)
			(layer "F.SilkS")
			(hide yes)
			(effects
				(font
					(size 1.27 1.27)
				)
			)
		)
		(property "Value" ""
			(at 0 0 270)
			(layer "F.Fab")
			(effects
				(font
					(size 1.27 1.27)
				)
			)
		)
		(duplicate_pad_numbers_are_jumpers no)
		(fp_line
			(start -0.299974 0.150114)
			(end -0.299974 -0.150114)
			(stroke
				(width 0.1)
				(type default)
			)
			(layer "F.Fab")
		)
		(fp_line
			(start 0.299974 0.150114)
			(end -0.299974 0.150114)
			(stroke
				(width 0.1)
				(type default)
			)
			(layer "F.Fab")
		)
		(fp_line
			(start -0.299974 -0.150114)
			(end 0.299974 -0.150114)
			(stroke
				(width 0.1)
				(type default)
			)
			(layer "F.Fab")
		)
		(fp_line
			(start 0.299974 -0.150114)
			(end 0.299974 0.150114)
			(stroke
				(width 0.1)
				(type default)
			)
			(layer "F.Fab")
		)
		(pad "1" smd rect
			(at -0.2667 0 270)
			(size 0.3048 0.381)
			(layers "F.Cu" "F.Mask" "F.Paste")
			(net "P5E_CPU0_P0_TX_C_DN<3>")
		)
		(pad "2" smd rect
			(at 0.2667 0 270)
			(size 0.3048 0.381)
			(layers "F.Cu" "F.Mask" "F.Paste")
			(net "P5E_CPU0_P0_TX_DN<3>")
		)
	)
	(footprint ""
		(layer "F.Cu")
		(at 42.527982 -387.764274)
		(property "Reference" "R599"
			(at 0 0 0)
			(layer "F.SilkS")
			(hide yes)
			(effects
				(font
					(size 1.27 1.27)
				)
			)
		)
		(property "Value" ""
			(at 0 0 0)
			(layer "F.Fab")
			(effects
				(font
					(size 1.27 1.27)
				)
			)
		)
		(duplicate_pad_numbers_are_jumpers no)
		(fp_line
			(start -0.32512 -0.175006)
			(end 0.32512 -0.175006)
			(stroke
				(width 0.1)
				(type default)
			)
			(layer "F.Fab")
		)
		(fp_line
			(start -0.32512 0.175006)
			(end -0.32512 -0.175006)
			(stroke
				(width 0.1)
				(type default)
			)
			(layer "F.Fab")
		)
		(fp_line
			(start 0.32512 -0.175006)
			(end 0.32512 0.175006)
			(stroke
				(width 0.1)
				(type default)
			)
			(layer "F.Fab")
		)
		(fp_line
			(start 0.32512 0.175006)
			(end -0.32512 0.175006)
			(stroke
				(width 0.1)
				(type default)
			)
			(layer "F.Fab")
		)
		(pad "1" smd rect
			(at -0.2667 0)
			(size 0.3048 0.381)
			(layers "F.Cu" "F.Mask" "F.Paste")
			(net "CLK_100M_RETIMER_CPU1_P0_R_DP")
		)
		(pad "2" smd rect
			(at 0.2667 0 180)
			(size 0.3048 0.381)
			(layers "F.Cu" "F.Mask" "F.Paste")
			(net "CLK_100M_RETIMER_CPU1_P0_DP")
		)
	)
)
